# S9S_MB_2U (Grand Teton) — schematic netlist excerpt (pin names and nets, part order shuffled) for the footprints in the layout excerpt that follows; sources: Cadence DE-HDL packaged netlist, KiCad conversion of 03242023_DA0F0TMBIJ0_F0T_Motherboard_J_brd_V01_OCP.brd

R4193  Q_RES  1K 1% CHIP  pkg 0402LF  page 170 : A = U273_3_ADD1 ; B = GND
R444  Q_RES  0 5% CHIP  pkg 0402LF  page 153 : A = OCP_SFF_USB2_3_DN ; B = USB2_3_DN

(kicad_pcb
	(version 20260206)
	(generator "pcbnew")
	(generator_version "10.0")
	(general
		(thickness 1.6)
		(legacy_teardrops no)
	)
	(paper "A4")
	(title_block
		(title "03242023_DA0F0TMBIJ0_F0T_Motherboard_J_brd_V01_OCP.brd")
		(comment 1 "Grand Teton / footprints 3831-3832 of 6105")
	)
	(layers
		(0 "F.Cu" signal "TOP")
		(4 "In1.Cu" signal "GND")
		(6 "In2.Cu" signal "IN1")
		(8 "In3.Cu" signal "GND1")
		(10 "In4.Cu" signal "IN2")
		(12 "In5.Cu" signal "GND2")
		(14 "In6.Cu" signal "IN3")
		(16 "In7.Cu" signal "GND3")
		(18 "In8.Cu" signal "VCC")
		(20 "In9.Cu" signal "VCC1")
		(22 "In10.Cu" signal "GND4")
		(24 "In11.Cu" signal "IN4")
		(26 "In12.Cu" signal "GND5")
		(28 "In13.Cu" signal "IN5")
		(30 "In14.Cu" signal "GND6")
		(32 "In15.Cu" signal "IN6")
		(34 "In16.Cu" signal "GND7")
		(2 "B.Cu" signal "BOTTOM")
		(9 "F.Adhes" user "F.Adhesive")
		(11 "B.Adhes" user "B.Adhesive")
		(13 "F.Paste" user "Package Geometry/Pastemask Top")
		(15 "B.Paste" user "Package Geometry/Pastemask Bottom")
		(5 "F.SilkS" user "Ref Des/Silkscreen Top")
		(7 "B.SilkS" user "Ref Des/Silkscreen Bottom")
		(1 "F.Mask" user "Board Geometry/Soldermask Top")
		(3 "B.Mask" user "Board Geometry/Soldermask Bottom")
		(17 "Dwgs.User" user "User.Drawings")
		(19 "Cmts.User" user "User.Comments")
		(21 "Eco1.User" user "User.Eco1")
		(23 "Eco2.User" user "User.Eco2")
		(25 "Edge.Cuts" user "Board Geometry/Outline")
		(27 "Margin" user)
		(31 "F.CrtYd" user "Package Geometry/Place Bound Top")
		(29 "B.CrtYd" user "Package Geometry/Place Bound Bottom")
		(35 "F.Fab" user "Ref Des/Assembly Top")
		(33 "B.Fab" user "Ref Des/Assembly Bottom")
	)
	(footprint ""
		(layer "F.Cu")
		(at 388.278116 -14.25321 90)
		(property "Reference" "R444"
			(at 0 0 90)
			(layer "F.SilkS")
			(hide yes)
			(effects
				(font
					(size 1.27 1.27)
				)
			)
		)
		(property "Value" ""
			(at 0 0 90)
			(layer "F.Fab")
			(effects
				(font
					(size 1.27 1.27)
				)
			)
		)
		(duplicate_pad_numbers_are_jumpers no)
		(fp_line
			(start 0.7874 -0.4064)
			(end 0.7874 0.4064)
			(stroke
				(width 0.1524)
				(type default)
			)
			(layer "F.SilkS")
		)
		(fp_line
			(start -0.7874 -0.4064)
			(end 0.7874 -0.4064)
			(stroke
				(width 0.1524)
				(type default)
			)
			(layer "F.SilkS")
		)
		(fp_line
			(start 0.7874 0.4064)
			(end -0.7874 0.4064)
			(stroke
				(width 0.1524)
				(type default)
			)
			(layer "F.SilkS")
		)
		(fp_line
			(start -0.7874 0.4064)
			(end -0.7874 -0.4064)
			(stroke
				(width 0.1524)
				(type default)
			)
			(layer "F.SilkS")
		)
		(fp_line
			(start -0.12065 -0.305054)
			(end -0.12065 -0.2794)
			(stroke
				(width 0.1)
				(type default)
			)
			(layer "F.Fab")
		)
		(fp_line
			(start -0.67945 -0.305054)
			(end -0.12065 -0.305054)
			(stroke
				(width 0.1)
				(type default)
			)
			(layer "F.Fab")
		)
		(fp_line
			(start 0.67945 -0.3048)
			(end 0.67945 0.3048)
			(stroke
				(width 0.1)
				(type default)
			)
			(layer "F.Fab")
		)
		(fp_line
			(start 0.12065 -0.3048)
			(end 0.67945 -0.3048)
			(stroke
				(width 0.1)
				(type default)
			)
			(layer "F.Fab")
		)
		(fp_line
			(start 0.12065 -0.2794)
			(end 0.12065 -0.3048)
			(stroke
				(width 0.1)
				(type default)
			)
			(layer "F.Fab")
		)
		(fp_line
			(start -0.12065 -0.2794)
			(end 0.12065 -0.2794)
			(stroke
				(width 0.1)
				(type default)
			)
			(layer "F.Fab")
		)
		(fp_line
			(start 0.120396 0.2794)
			(end -0.12065 0.2794)
			(stroke
				(width 0.1)
				(type default)
			)
			(layer "F.Fab")
		)
		(fp_line
			(start -0.12065 0.2794)
			(end -0.12065 0.3048)
			(stroke
				(width 0.1)
				(type default)
			)
			(layer "F.Fab")
		)
		(fp_line
			(start 0.67945 0.3048)
			(end 0.120396 0.3048)
			(stroke
				(width 0.1)
				(type default)
			)
			(layer "F.Fab")
		)
		(fp_line
			(start 0.120396 0.3048)
			(end 0.120396 0.2794)
			(stroke
				(width 0.1)
				(type default)
			)
			(layer "F.Fab")
		)
		(fp_line
			(start -0.12065 0.3048)
			(end -0.67945 0.3048)
			(stroke
				(width 0.1)
				(type default)
			)
			(layer "F.Fab")
		)
		(fp_line
			(start -0.67945 0.3048)
			(end -0.67945 -0.305054)
			(stroke
				(width 0.1)
				(type default)
			)
			(layer "F.Fab")
		)
		(pad "1" smd circle
			(at -0.40005 0 90)
			(size 0 0)
			(layers "F.Cu" "F.Mask" "F.Paste")
			(net "OCP_SFF_USB2_3_DN")
		)
		(pad "2" smd circle
			(at 0.40005 0 90)
			(size 0 0)
			(layers "F.Cu" "F.Mask" "F.Paste")
			(net "USB2_3_DN")
		)
	)
	(footprint ""
		(layer "F.Cu")
		(at 120.326658 -15.526766)
		(property "Reference" "R4193"
			(at 0 0 0)
			(layer "F.SilkS")
			(hide yes)
			(effects
				(font
					(size 1.27 1.27)
				)
			)
		)
		(property "Value" ""
			(at 0 0 0)
			(layer "F.Fab")
			(effects
				(font
					(size 1.27 1.27)
				)
			)
		)
		(duplicate_pad_numbers_are_jumpers no)
		(fp_line
			(start -0.7874 -0.4064)
			(end 0.7874 -0.4064)
			(stroke
				(width 0.1524)
				(type default)
			)
			(layer "F.SilkS")
		)
		(fp_line
			(start -0.7874 0.4064)
			(end -0.7874 -0.4064)
			(stroke
				(width 0.1524)
				(type default)
			)
			(layer "F.SilkS")
		)
		(fp_line
			(start 0.7874 -0.4064)
			(end 0.7874 0.4064)
			(stroke
				(width 0.1524)
				(type default)
			)
			(layer "F.SilkS")
		)
		(fp_line
			(start 0.7874 0.4064)
			(end -0.7874 0.4064)
			(stroke
				(width 0.1524)
				(type default)
			)
			(layer "F.SilkS")
		)
		(fp_line
			(start -0.67945 -0.305054)
			(end -0.12065 -0.305054)
			(stroke
				(width 0.1)
				(type default)
			)
			(layer "F.Fab")
		)
		(fp_line
			(start -0.67945 0.3048)
			(end -0.67945 -0.305054)
			(stroke
				(width 0.1)
				(type default)
			)
			(layer "F.Fab")
		)
		(fp_line
			(start -0.12065 -0.305054)
			(end -0.12065 -0.2794)
			(stroke
				(width 0.1)
				(type default)
			)
			(layer "F.Fab")
		)
		(fp_line
			(start -0.12065 -0.2794)
			(end 0.12065 -0.2794)
			(stroke
				(width 0.1)
				(type default)
			)
			(layer "F.Fab")
		)
		(fp_line
			(start -0.12065 0.2794)
			(end -0.12065 0.3048)
			(stroke
				(width 0.1)
				(type default)
			)
			(layer "F.Fab")
		)
		(fp_line
			(start -0.12065 0.3048)
			(end -0.67945 0.3048)
			(stroke
				(width 0.1)
				(type default)
			)
			(layer "F.Fab")
		)
		(fp_line
			(start 0.120396 0.2794)
			(end -0.12065 0.2794)
			(stroke
				(width 0.1)
				(type default)
			)
			(layer "F.Fab")
		)
		(fp_line
			(start 0.120396 0.3048)
			(end 0.120396 0.2794)
			(stroke
				(width 0.1)
				(type default)
			)
			(layer "F.Fab")
		)
		(fp_line
			(start 0.12065 -0.3048)
			(end 0.67945 -0.3048)
			(stroke
				(width 0.1)
				(type default)
			)
			(layer "F.Fab")
		)
		(fp_line
			(start 0.12065 -0.2794)
			(end 0.12065 -0.3048)
			(stroke
				(width 0.1)
				(type default)
			)
			(layer "F.Fab")
		)
		(fp_line
			(start 0.67945 -0.3048)
			(end 0.67945 0.3048)
			(stroke
				(width 0.1)
				(type default)
			)
			(layer "F.Fab")
		)
		(fp_line
			(start 0.67945 0.3048)
			(end 0.120396 0.3048)
			(stroke
				(width 0.1)
				(type default)
			)
			(layer "F.Fab")
		)
		(pad "1" smd circle
			(at -0.40005 0)
			(size 0 0)
			(layers "F.Cu" "F.Mask" "F.Paste")
			(net "U273_3_ADD1")
		)
		(pad "2" smd circle
			(at 0.40005 0)
			(size 0 0)
			(layers "F.Cu" "F.Mask" "F.Paste")
			(net "GND")
		)
	)
)
